(kicad_pcb
	(version 20241229)
	(generator "pcbnew")
	(generator_version "9.0")
	(general
		(thickness 1.6642)
		(legacy_teardrops no)
	)
	(paper "A3")
	(title_block
		(title "PolarFire SoM")
		(date "2025-07-22")
		(rev "1.1.4")
		(company "Antmicro Ltd")
		(comment 1 "www.antmicro.com")
		(comment 9 "footprint 85 of 470 (U1), pads 283-358 of 484")
	)
	(layers
		(0 "F.Cu" mixed)
		(4 "In1.Cu" power)
		(6 "In2.Cu" signal)
		(8 "In3.Cu" power)
		(10 "In4.Cu" signal)
		(12 "In5.Cu" power)
		(14 "In6.Cu" power)
		(16 "In7.Cu" signal)
		(18 "In8.Cu" power)
		(20 "In9.Cu" signal)
		(22 "In10.Cu" power)
		(24 "In11.Cu" signal)
		(26 "In12.Cu" signal)
		(2 "B.Cu" mixed)
		(9 "F.Adhes" user "F.Adhesive")
		(11 "B.Adhes" user "B.Adhesive")
		(13 "F.Paste" user)
		(15 "B.Paste" user)
		(5 "F.SilkS" user "F.Silkscreen")
		(7 "B.SilkS" user "B.Silkscreen")
		(1 "F.Mask" user)
		(3 "B.Mask" user)
		(17 "Dwgs.User" user "User.Drawings")
		(19 "Cmts.User" user "User.Comments")
		(21 "Eco1.User" user "User.Eco1")
		(23 "Eco2.User" user "User.Eco2")
		(25 "Edge.Cuts" user)
		(27 "Margin" user)
		(31 "F.CrtYd" user "F.Courtyard")
		(29 "B.CrtYd" user "B.Courtyard")
		(35 "F.Fab" user)
		(33 "B.Fab" user)
	)
	(footprint "antmicro-footprints:BGA-484_19x19mm_Layout22x22_P0.8mm_FCVG484"
		(layer "F.Cu")
		(at 197.699 132.701 -90)
		(descr "FCVG484, 19.0x19.0mm, 484 Ball, 22x22 Layout, 0.8mm Pitch")
		(tags "BGA 484 0.8")
		(property "Reference" "U1"
			(at 0 -10.8 270)
			(layer "F.SilkS")
			(effects
				(font
					(size 0.7 0.7)
					(thickness 0.15)
				)
				(justify left bottom)
			)
		)
		(property "Value" "MPFS250T-FCVG484"
			(at 0 11.5 270)
			(layer "F.Fab")
			(hide yes)
			(effects
				(font
					(size 0.7 0.7)
					(thickness 0.15)
				)
				(justify left bottom)
			)
		)
		(property "Datasheet" "https://ww1.microchip.com/downloads/aemDocuments/documents/FPGA/ProductDocuments/DataSheets/PolarFire-SoC-Datasheet-DS00004248.pdf"
			(at 0 0 270)
			(layer "F.Fab")
			(hide yes)
			(effects
				(font
					(size 1.27 1.27)
					(thickness 0.15)
				)
			)
		)
		(property "Description" "RISC-V System On Chip (SOC) IC PolarFire® FPGA - 254K Logic Modules 484-FCBGA (19x19)"
			(at 0 0 270)
			(layer "F.Fab")
			(hide yes)
			(effects
				(font
					(size 1.27 1.27)
					(thickness 0.15)
				)
			)
		)
		(property "MPN" "MPFS250T-FCVG484E"
			(at 0 0 270)
			(unlocked yes)
			(layer "F.Fab")
			(hide yes)
			(effects
				(font
					(size 1 1)
					(thickness 0.15)
				)
			)
		)
		(property "Manufacturer" "Microchip Technology"
			(at 0 0 270)
			(unlocked yes)
			(layer "F.Fab")
			(hide yes)
			(effects
				(font
					(size 1 1)
					(thickness 0.15)
				)
			)
		)
		(property "VSD_class" "MPFS250T"
			(at 0 0 270)
			(unlocked yes)
			(layer "F.Fab")
			(hide yes)
			(effects
				(font
					(size 1 1)
					(thickness 0.15)
				)
			)
		)
		(property "Author" "Antmicro"
			(at 0 0 270)
			(unlocked yes)
			(layer "F.Fab")
			(hide yes)
			(effects
				(font
					(size 1 1)
					(thickness 0.15)
				)
			)
		)
		(property "License" "Apache-2.0"
			(at 0 0 270)
			(unlocked yes)
			(layer "F.Fab")
			(hide yes)
			(effects
				(font
					(size 1 1)
					(thickness 0.15)
				)
			)
		)
		(sheetname "/FPGA Config/")
		(sheetfile "fpga-config.kicad_sch")
		(attr smd)
		(pad "L19" smd circle
			(at 5.999 -0.401 270)
			(size 0.45 0.45)
			(layers "F.Cu" "F.Mask" "F.Paste")
			(net 461 "/PCIe/PF_PCIe_CLK_P")
			(pinfunction "XCVR_0A_REFCLK_P")
			(pintype "input")
			(die_length 5.39647)
		)
		(pad "L20" smd circle
			(at 6.799 -0.401 270)
			(size 0.45 0.45)
			(layers "F.Cu" "F.Mask" "F.Paste")
			(net 562 "/PCIe/PF_PCIe_CLK_N")
			(pinfunction "XCVR_0A_REFCLK_N")
			(pintype "input")
			(die_length 5.40211)
		)
		(pad "L21" smd circle
			(at 7.599 -0.401 270)
			(size 0.45 0.45)
			(layers "F.Cu" "F.Mask" "F.Paste")
			(net 47 "+1V05")
			(pinfunction "VDDA")
			(pintype "passive")
		)
		(pad "L22" smd circle
			(at 8.4 -0.401 270)
			(size 0.45 0.45)
			(layers "F.Cu" "F.Mask" "F.Paste")
			(net 417 "GND")
			(pinfunction "VSS")
			(pintype "passive")
		)
		(pad "M1" smd circle
			(at -8.401 0.4 270)
			(size 0.45 0.45)
			(layers "F.Cu" "F.Mask" "F.Paste")
			(net 417 "GND")
			(pinfunction "VSS")
			(pintype "passive")
		)
		(pad "M2" smd circle
			(at -7.6 0.4 270)
			(size 0.45 0.45)
			(layers "F.Cu" "F.Mask" "F.Paste")
			(net 403 "unconnected-(U1G-MSS_DDR_BG1-PadM2)")
			(pinfunction "MSS_DDR_BG1")
			(pintype "bidirectional+no_connect")
			(die_length 6.23809)
		)
		(pad "M3" smd circle
			(at -6.8 0.4 270)
			(size 0.45 0.45)
			(layers "F.Cu" "F.Mask" "F.Paste")
			(net 404 "unconnected-(U1G-MSS_DDR_CS1-PadM3)")
			(pinfunction "MSS_DDR_CS1")
			(pintype "bidirectional+no_connect")
			(die_length 6.42569)
		)
		(pad "M4" smd circle
			(at -6 0.4 270)
			(size 0.45 0.45)
			(layers "F.Cu" "F.Mask" "F.Paste")
			(net 405 "unconnected-(U1G-MSS_DDR_ODT1-PadM4)")
			(pinfunction "MSS_DDR_ODT1")
			(pintype "bidirectional+no_connect")
			(die_length 6.26668)
		)
		(pad "M5" smd circle
			(at -5.201 0.4 270)
			(size 0.45 0.45)
			(layers "F.Cu" "F.Mask" "F.Paste")
			(net 407 "unconnected-(U1G-MSS_DDR_PARITY-PadM5)")
			(pinfunction "MSS_DDR_PARITY")
			(pintype "bidirectional+no_connect")
			(die_length 6.72139)
		)
		(pad "M6" smd circle
			(at -4.401 0.4 270)
			(size 0.45 0.45)
			(layers "F.Cu" "F.Mask" "F.Paste")
			(net 50 "+3V3")
			(pinfunction "VDDI5")
			(pintype "power_in")
		)
		(pad "M7" smd circle
			(at -3.601 0.4 270)
			(size 0.45 0.45)
			(layers "F.Cu" "F.Mask" "F.Paste")
			(net 408 "unconnected-(U1F-MSS_SGMII_TXP1-PadM7)")
			(pinfunction "MSS_SGMII_TXP1")
			(pintype "bidirectional+no_connect")
			(die_length 10.1667)
		)
		(pad "M8" smd circle
			(at -2.8 0.4 270)
			(size 0.45 0.45)
			(layers "F.Cu" "F.Mask" "F.Paste")
			(net 50 "+3V3")
			(pinfunction "VDDI5")
			(pintype "passive")
		)
		(pad "M9" smd circle
			(at -2 0.4 270)
			(size 0.45 0.45)
			(layers "F.Cu" "F.Mask" "F.Paste")
			(net 417 "GND")
			(pinfunction "VSS")
			(pintype "passive")
		)
		(pad "M10" smd circle
			(at -1.2 0.4 270)
			(size 0.45 0.45)
			(layers "F.Cu" "F.Mask" "F.Paste")
			(net 519 "SD_VDD_AUX")
			(pinfunction "VDDAUX4")
			(pintype "power_in")
		)
		(pad "M11" smd circle
			(at -0.401 0.4 270)
			(size 0.45 0.45)
			(layers "F.Cu" "F.Mask" "F.Paste")
			(net 417 "GND")
			(pinfunction "VSS")
			(pintype "passive")
		)
		(pad "M12" smd circle
			(at 0.4 0.4 270)
			(size 0.45 0.45)
			(layers "F.Cu" "F.Mask" "F.Paste")
			(net 47 "+1V05")
			(pinfunction "VDD")
			(pintype "passive")
		)
		(pad "M13" smd circle
			(at 1.199 0.4 270)
			(size 0.45 0.45)
			(layers "F.Cu" "F.Mask" "F.Paste")
			(net 417 "GND")
			(pinfunction "VSS")
			(pintype "passive")
		)
		(pad "M14" smd circle
			(at 1.999 0.4 270)
			(size 0.45 0.45)
			(layers "F.Cu" "F.Mask" "F.Paste")
			(net 47 "+1V05")
			(pinfunction "VDD")
			(pintype "passive")
		)
		(pad "M15" smd circle
			(at 2.799 0.4 270)
			(size 0.45 0.45)
			(layers "F.Cu" "F.Mask" "F.Paste")
			(net 417 "GND")
			(pinfunction "VSS")
			(pintype "passive")
		)
		(pad "M16" smd circle
			(at 3.6 0.4 270)
			(size 0.45 0.45)
			(layers "F.Cu" "F.Mask" "F.Paste")
			(net 47 "+1V05")
			(pinfunction "VDD")
			(pintype "passive")
		)
		(pad "M17" smd circle
			(at 4.4 0.4 270)
			(size 0.45 0.45)
			(layers "F.Cu" "F.Mask" "F.Paste")
			(net 417 "GND")
			(pinfunction "VSS")
			(pintype "passive")
		)
		(pad "M18" smd circle
			(at 5.2 0.4 270)
			(size 0.45 0.45)
			(layers "F.Cu" "F.Mask" "F.Paste")
			(net 418 "+2V5")
			(pinfunction "VDDA25")
			(pintype "passive")
		)
		(pad "M19" smd circle
			(at 5.999 0.4 270)
			(size 0.45 0.45)
			(layers "F.Cu" "F.Mask" "F.Paste")
			(net 417 "GND")
			(pinfunction "VSS")
			(pintype "passive")
		)
		(pad "M20" smd circle
			(at 6.799 0.4 270)
			(size 0.45 0.45)
			(layers "F.Cu" "F.Mask" "F.Paste")
			(net 417 "GND")
			(pinfunction "VSS")
			(pintype "passive")
		)
		(pad "M21" smd circle
			(at 7.599 0.4 270)
			(size 0.45 0.45)
			(layers "F.Cu" "F.Mask" "F.Paste")
			(net 139 "/Bottom Connector/PCIE.RXD2_N")
			(pinfunction "XCVR_0_RX2_N")
			(pintype "input")
			(die_length 5.06127)
		)
		(pad "M22" smd circle
			(at 8.4 0.4 270)
			(size 0.45 0.45)
			(layers "F.Cu" "F.Mask" "F.Paste")
			(net 140 "/Bottom Connector/PCIE.RXD2_P")
			(pinfunction "XCVR_0_RX2_P")
			(pintype "input")
			(die_length 5.05345)
		)
		(pad "N1" smd circle
			(at -8.401 1.199 270)
			(size 0.45 0.45)
			(layers "F.Cu" "F.Mask" "F.Paste")
			(net 412 "unconnected-(U1G-MSS_DDR_BG0-PadN1)")
			(pinfunction "MSS_DDR_BG0")
			(pintype "bidirectional+no_connect")
			(die_length 5.69155)
		)
		(pad "N2" smd circle
			(at -7.6 1.199 270)
			(size 0.45 0.45)
			(layers "F.Cu" "F.Mask" "F.Paste")
			(net 413 "unconnected-(U1G-MSS_DDR_CKE1-PadN2)")
			(pinfunction "MSS_DDR_CKE1")
			(pintype "bidirectional+no_connect")
			(die_length 4.87548)
		)
		(pad "N3" smd circle
			(at -6.8 1.199 270)
			(size 0.45 0.45)
			(layers "F.Cu" "F.Mask" "F.Paste")
			(net 2 "+1V1")
			(pinfunction "VDDI6")
			(pintype "passive")
		)
		(pad "N4" smd circle
			(at -6 1.199 270)
			(size 0.45 0.45)
			(layers "F.Cu" "F.Mask" "F.Paste")
			(net 414 "unconnected-(U1G-MSS_DDR_ALERT_N-PadN4)")
			(pinfunction "MSS_DDR_ALERT_N")
			(pintype "bidirectional+no_connect")
			(die_length 5.90664)
		)
		(pad "N5" smd circle
			(at -5.201 1.199 270)
			(size 0.45 0.45)
			(layers "F.Cu" "F.Mask" "F.Paste")
			(net 415 "unconnected-(U1G-MSS_DDR_ACT_N-PadN5)")
			(pinfunction "MSS_DDR_ACT_N")
			(pintype "bidirectional+no_connect")
			(die_length 6.32348)
		)
		(pad "N6" smd circle
			(at -4.401 1.199 270)
			(size 0.45 0.45)
			(layers "F.Cu" "F.Mask" "F.Paste")
			(net 43 "/Ethernet/SGMII.TX0_P")
			(pinfunction "MSS_SGMII_TXP0")
			(pintype "bidirectional")
			(die_length 8.82437)
		)
		(pad "N7" smd circle
			(at -3.601 1.199 270)
			(size 0.45 0.45)
			(layers "F.Cu" "F.Mask" "F.Paste")
			(net 68 "/Ethernet/SGMII.TX0_N")
			(pinfunction "MSS_SGMII_TXN0")
			(pintype "bidirectional")
			(die_length 8.84193)
		)
		(pad "N8" smd circle
			(at -2.8 1.199 270)
			(size 0.45 0.45)
			(layers "F.Cu" "F.Mask" "F.Paste")
			(net 416 "unconnected-(U1F-MSS_SGMII_TXN1-PadN8)")
			(pinfunction "MSS_SGMII_TXN1")
			(pintype "bidirectional+no_connect")
			(die_length 10.1512)
		)
		(pad "N9" smd circle
			(at -2 1.199 270)
			(size 0.45 0.45)
			(layers "F.Cu" "F.Mask" "F.Paste")
			(net 519 "SD_VDD_AUX")
			(pinfunction "VDDAUX4")
			(pintype "passive")
		)
		(pad "N10" smd circle
			(at -1.2 1.199 270)
			(size 0.45 0.45)
			(layers "F.Cu" "F.Mask" "F.Paste")
			(net 417 "GND")
			(pinfunction "VSS")
			(pintype "passive")
		)
		(pad "N11" smd circle
			(at -0.401 1.199 270)
			(size 0.45 0.45)
			(layers "F.Cu" "F.Mask" "F.Paste")
			(net 47 "+1V05")
			(pinfunction "VDD")
			(pintype "passive")
		)
		(pad "N12" smd circle
			(at 0.4 1.199 270)
			(size 0.45 0.45)
			(layers "F.Cu" "F.Mask" "F.Paste")
			(net 417 "GND")
			(pinfunction "VSS")
			(pintype "passive")
		)
		(pad "N13" smd circle
			(at 1.199 1.199 270)
			(size 0.45 0.45)
			(layers "F.Cu" "F.Mask" "F.Paste")
			(net 47 "+1V05")
			(pinfunction "VDD")
			(pintype "passive")
		)
		(pad "N14" smd circle
			(at 1.999 1.199 270)
			(size 0.45 0.45)
			(layers "F.Cu" "F.Mask" "F.Paste")
			(net 417 "GND")
			(pinfunction "VSS")
			(pintype "passive")
		)
		(pad "N15" smd circle
			(at 2.799 1.199 270)
			(size 0.45 0.45)
			(layers "F.Cu" "F.Mask" "F.Paste")
			(net 47 "+1V05")
			(pinfunction "VDD")
			(pintype "passive")
		)
		(pad "N16" smd circle
			(at 3.6 1.199 270)
			(size 0.45 0.45)
			(layers "F.Cu" "F.Mask" "F.Paste")
			(net 417 "GND")
			(pinfunction "VSS")
			(pintype "passive")
		)
		(pad "N17" smd circle
			(at 4.4 1.199 270)
			(size 0.45 0.45)
			(layers "F.Cu" "F.Mask" "F.Paste")
			(net 47 "+1V05")
			(pinfunction "VDD")
			(pintype "passive")
		)
		(pad "N18" smd circle
			(at 5.2 1.199 270)
			(size 0.45 0.45)
			(layers "F.Cu" "F.Mask" "F.Paste")
			(net 417 "GND")
			(pinfunction "VSS")
			(pintype "passive")
		)
		(pad "N19" smd circle
			(at 5.999 1.199 270)
			(size 0.45 0.45)
			(layers "F.Cu" "F.Mask" "F.Paste")
			(net 419 "unconnected-(U1H-XCVR_0B_REFCLK_P-PadN19)")
			(pinfunction "XCVR_0B_REFCLK_P")
			(pintype "input+no_connect")
			(die_length 3.66682)
		)
		(pad "N20" smd circle
			(at 6.799 1.199 270)
			(size 0.45 0.45)
			(layers "F.Cu" "F.Mask" "F.Paste")
			(net 420 "unconnected-(U1H-XCVR_0B_REFCLK_N-PadN20)")
			(pinfunction "XCVR_0B_REFCLK_N")
			(pintype "input+no_connect")
			(die_length 3.67223)
		)
		(pad "N21" smd circle
			(at 7.599 1.199 270)
			(size 0.45 0.45)
			(layers "F.Cu" "F.Mask" "F.Paste")
			(net 47 "+1V05")
			(pinfunction "VDDA")
			(pintype "passive")
		)
		(pad "N22" smd circle
			(at 8.4 1.199 270)
			(size 0.45 0.45)
			(layers "F.Cu" "F.Mask" "F.Paste")
			(net 417 "GND")
			(pinfunction "VSS")
			(pintype "passive")
		)
		(pad "P1" smd circle
			(at -8.401 1.999 270)
			(size 0.45 0.45)
			(layers "F.Cu" "F.Mask" "F.Paste")
			(net 425 "unconnected-(U1G-MSS_DDR_A12-PadP1)")
			(pinfunction "MSS_DDR_A12")
			(pintype "bidirectional+no_connect")
			(die_length 5.26134)
		)
		(pad "P2" smd circle
			(at -7.6 1.999 270)
			(size 0.45 0.45)
			(layers "F.Cu" "F.Mask" "F.Paste")
			(net 426 "unconnected-(U1G-MSS_DDR_A13-PadP2)")
			(pinfunction "MSS_DDR_A13")
			(pintype "bidirectional+no_connect")
			(die_length 4.7942)
		)
		(pad "P3" smd circle
			(at -6.8 1.999 270)
			(size 0.45 0.45)
			(layers "F.Cu" "F.Mask" "F.Paste")
			(net 427 "unconnected-(U1G-MSS_DDR_A14-PadP3)")
			(pinfunction "MSS_DDR_A14")
			(pintype "bidirectional+no_connect")
			(die_length 5.81429)
		)
		(pad "P4" smd circle
			(at -6 1.999 270)
			(size 0.45 0.45)
			(layers "F.Cu" "F.Mask" "F.Paste")
			(net 429 "unconnected-(U1G-MSS_DDR_BA0-PadP4)")
			(pinfunction "MSS_DDR_BA0")
			(pintype "bidirectional+no_connect")
			(die_length 4.15969)
		)
		(pad "P5" smd circle
			(at -5.201 1.999 270)
			(size 0.45 0.45)
			(layers "F.Cu" "F.Mask" "F.Paste")
			(net 417 "GND")
			(pinfunction "VSS")
			(pintype "passive")
		)
		(pad "P6" smd circle
			(at -4.401 1.999 270)
			(size 0.45 0.45)
			(layers "F.Cu" "F.Mask" "F.Paste")
			(net 431 "unconnected-(U1G-MSS_DDR_A6-PadP6)")
			(pinfunction "MSS_DDR_A6")
			(pintype "bidirectional+no_connect")
			(die_length 5.75834)
		)
		(pad "P7" smd circle
			(at -3.601 1.999 270)
			(size 0.45 0.45)
			(layers "F.Cu" "F.Mask" "F.Paste")
			(net 432 "unconnected-(U1G-MSS_DDR_A8-PadP7)")
			(pinfunction "MSS_DDR_A8")
			(pintype "bidirectional+no_connect")
			(die_length 5.75727)
		)
		(pad "P8" smd circle
			(at -2.8 1.999 270)
			(size 0.45 0.45)
			(layers "F.Cu" "F.Mask" "F.Paste")
			(net 567 "/FPGA MSS/LPDDR4.DQ31")
			(pinfunction "MSS_DDR_DQ31")
			(pintype "bidirectional")
			(die_length 7.47712)
		)
		(pad "P9" smd circle
			(at -2 1.999 270)
			(size 0.45 0.45)
			(layers "F.Cu" "F.Mask" "F.Paste")
			(net 417 "GND")
			(pinfunction "VSS")
			(pintype "passive")
		)
		(pad "P10" smd circle
			(at -1.2 1.999 270)
			(size 0.45 0.45)
			(layers "F.Cu" "F.Mask" "F.Paste")
			(net 48 "+1V8")
			(pinfunction "VDD18")
			(pintype "power_in")
		)
		(pad "P11" smd circle
			(at -0.401 1.999 270)
			(size 0.45 0.45)
			(layers "F.Cu" "F.Mask" "F.Paste")
			(net 417 "GND")
			(pinfunction "VSS")
			(pintype "passive")
		)
		(pad "P12" smd circle
			(at 0.4 1.999 270)
			(size 0.45 0.45)
			(layers "F.Cu" "F.Mask" "F.Paste")
			(net 48 "+1V8")
			(pinfunction "VDD18")
			(pintype "passive")
		)
		(pad "P13" smd circle
			(at 1.199 1.999 270)
			(size 0.45 0.45)
			(layers "F.Cu" "F.Mask" "F.Paste")
			(net 417 "GND")
			(pinfunction "VSS")
			(pintype "passive")
		)
		(pad "P14" smd circle
			(at 1.999 1.999 270)
			(size 0.45 0.45)
			(layers "F.Cu" "F.Mask" "F.Paste")
			(net 48 "+1V8")
			(pinfunction "VDD18")
			(pintype "passive")
		)
		(pad "P15" smd circle
			(at 2.799 1.999 270)
			(size 0.45 0.45)
			(layers "F.Cu" "F.Mask" "F.Paste")
			(net 417 "GND")
			(pinfunction "VSS")
			(pintype "passive")
		)
		(pad "P16" smd circle
			(at 3.6 1.999 270)
			(size 0.45 0.45)
			(layers "F.Cu" "F.Mask" "F.Paste")
			(net 48 "+1V8")
			(pinfunction "VDD18")
			(pintype "passive")
		)
		(pad "P17" smd circle
			(at 4.4 1.999 270)
			(size 0.45 0.45)
			(layers "F.Cu" "F.Mask" "F.Paste")
			(net 417 "GND")
			(pinfunction "VSS")
			(pintype "passive")
		)
		(pad "P18" smd circle
			(at 5.2 1.999 270)
			(size 0.45 0.45)
			(layers "F.Cu" "F.Mask" "F.Paste")
			(net 418 "+2V5")
			(pinfunction "VDD_XCVR_CLK")
			(pintype "passive")
		)
		(pad "P19" smd circle
			(at 5.999 1.999 270)
			(size 0.45 0.45)
			(layers "F.Cu" "F.Mask" "F.Paste")
			(net 47 "+1V05")
			(pinfunction "VDDA")
			(pintype "passive")
		)
		(pad "P20" smd circle
			(at 6.799 1.999 270)
			(size 0.45 0.45)
			(layers "F.Cu" "F.Mask" "F.Paste")
			(net 417 "GND")
			(pinfunction "VSS")
			(pintype "passive")
		)
		(pad "P21" smd circle
			(at 7.599 1.999 270)
			(size 0.45 0.45)
			(layers "F.Cu" "F.Mask" "F.Paste")
			(net 93 "/PCIe/XCVR_TX2_N")
			(pinfunction "XCVR_0_TX2_N")
			(pintype "output")
			(die_length 5.22418)
		)
		(pad "P22" smd circle
			(at 8.4 1.999 270)
			(size 0.45 0.45)
			(layers "F.Cu" "F.Mask" "F.Paste")
			(net 95 "/PCIe/XCVR_TX2_P")
			(pinfunction "XCVR_0_TX2_P")
			(pintype "output")
			(die_length 5.20705)
		)
		(pad "R1" smd circle
			(at -8.401 2.799 270)
			(size 0.45 0.45)
			(layers "F.Cu" "F.Mask" "F.Paste")
			(net 433 "unconnected-(U1G-MSS_DDR_A11-PadR1)")
			(pinfunction "MSS_DDR_A11")
			(pintype "bidirectional+no_connect")
			(die_length 5.25487)
		)
		(pad "R2" smd circle
			(at -7.6 2.799 270)
			(size 0.45 0.45)
			(layers "F.Cu" "F.Mask" "F.Paste")
			(net 417 "GND")
			(pinfunction "VSS")
			(pintype "passive")
		)
		(pad "R3" smd circle
			(at -6.8 2.799 270)
			(size 0.45 0.45)
			(layers "F.Cu" "F.Mask" "F.Paste")
			(net 434 "unconnected-(U1G-MSS_DDR_A15-PadR3)")
			(pinfunction "MSS_DDR_A15")
			(pintype "bidirectional+no_connect")
			(die_length 5.32263)
		)
		(pad "R4" smd circle
			(at -6 2.799 270)
			(size 0.45 0.45)
			(layers "F.Cu" "F.Mask" "F.Paste")
			(net 435 "unconnected-(U1G-MSS_DDR_A16-PadR4)")
			(pinfunction "MSS_DDR_A16")
			(pintype "bidirectional+no_connect")
			(die_length 4.07803)
		)
		(pad "R5" smd circle
			(at -5.201 2.799 270)
			(size 0.45 0.45)
			(layers "F.Cu" "F.Mask" "F.Paste")
			(net 568 "/FPGA MSS/LPDDR4.CA5_A")
			(pinfunction "MSS_DDR_A5")
			(pintype "bidirectional")
			(die_length 6.19696)
		)
		(pad "R6" smd circle
			(at -4.401 2.799 270)
			(size 0.45 0.45)
			(layers "F.Cu" "F.Mask" "F.Paste")
			(net 583 "/FPGA MSS/LPDDR4.CA4_A")
			(pinfunction "MSS_DDR_A4")
			(pintype "bidirectional")
			(die_length 6.05244)
		)
	)
)
